(kicad_pcb
	(version 20260206)
	(generator "pcbnew")
	(generator_version "10.0")
	(general
		(thickness 1.6)
		(legacy_teardrops no)
	)
	(paper "A4")
	(title_block
		(title "panther-plus-userver — 13130-1b_20150205.brd")
		(comment 1 "Honey Badger (Wiwynn) / footprints 536-542 of 1509")
	)
	(layers
		(0 "F.Cu" signal "TOP")
		(4 "In1.Cu" signal "L2")
		(6 "In2.Cu" signal "L3")
		(8 "In3.Cu" signal "L4")
		(10 "In4.Cu" signal "L5")
		(12 "In5.Cu" signal "L6")
		(14 "In6.Cu" signal "L7")
		(16 "In7.Cu" signal "L8")
		(18 "In8.Cu" signal "L9")
		(20 "In9.Cu" signal "L10")
		(22 "In10.Cu" signal "L11")
		(2 "B.Cu" signal "BOTTOM")
		(9 "F.Adhes" user "F.Adhesive")
		(11 "B.Adhes" user "B.Adhesive")
		(13 "F.Paste" user "Package Geometry/Pastemask Top")
		(15 "B.Paste" user "Package Geometry/Pastemask Bottom")
		(5 "F.SilkS" user "Ref Des/Silkscreen Top")
		(7 "B.SilkS" user "Ref Des/Silkscreen Bottom")
		(1 "F.Mask" user "Board Geometry/Soldermask Top")
		(3 "B.Mask" user "Board Geometry/Soldermask Bottom")
		(17 "Dwgs.User" user "User.Drawings")
		(19 "Cmts.User" user "User.Comments")
		(21 "Eco1.User" user "User.Eco1")
		(23 "Eco2.User" user "User.Eco2")
		(25 "Edge.Cuts" user "Board Geometry/Outline")
		(27 "Margin" user)
		(31 "F.CrtYd" user "Package Geometry/Place Bound Top")
		(29 "B.CrtYd" user "Package Geometry/Place Bound Bottom")
		(35 "F.Fab" user "Ref Des/Assembly Top")
		(33 "B.Fab" user "Ref Des/Assembly Bottom")
	)
	(footprint ""
		(layer "F.Cu")
		(at 8.509 -59.182 90)
		(property "Reference" "C40"
			(at 0 0 90)
			(layer "F.SilkS")
			(hide yes)
			(effects
				(font
					(size 1.27 1.27)
				)
			)
		)
		(property "Value" "SCD1U16V2KX-3GP"
			(at 1.1811 -2.7051 90)
			(unlocked yes)
			(layer "F.Fab")
			(hide yes)
			(effects
				(font
					(size 1.016 1.016)
					(thickness 0.1524)
				)
			)
		)
		(property "Device Type" "C402H22"
			(at 1.1811 -4.2291 90)
			(unlocked yes)
			(layer "F.Fab")
			(hide yes)
			(effects
				(font
					(size 1.016 1.016)
					(thickness 0.1524)
				)
			)
		)
		(duplicate_pad_numbers_are_jumpers no)
		(fp_rect
			(start -0.381 0.7366)
			(end 0.381 -0.7366)
			(stroke
				(width 0)
				(type default)
			)
			(fill no)
			(layer "F.CrtYd")
		)
		(fp_rect
			(start -0.381 0.7366)
			(end 0.381 -0.7366)
			(stroke
				(width 0)
				(type default)
			)
			(fill no)
			(layer "F.Fab")
		)
		(pad "1" smd custom
			(at 0 -0.4572 90)
			(size 0.1143 0.1143)
			(layers "F.Cu" "F.Mask" "F.Paste")
			(net "P2E_CPU_NGFF_TX_DP14")
			(options
				(clearance outline)
				(anchor circle)
			)
			(primitives
				(gr_poly
					(pts
						(arc
							(start -0.254 -0.1778)
							(mid -0.239121 -0.213721)
							(end -0.2032 -0.2286)
						)
						(arc
							(start 0.2032 -0.2286)
							(mid 0.239121 -0.213721)
							(end 0.254 -0.1778)
						)
						(arc
							(start 0.254 0.1778)
							(mid 0.239121 0.213721)
							(end 0.2032 0.2286)
						)
						(arc
							(start -0.2032 0.2286)
							(mid -0.239121 0.213721)
							(end -0.254 0.1778)
						)
					)
					(width 0)
					(fill yes)
				)
			)
		)
		(pad "2" smd custom
			(at 0 0.4572 90)
			(size 0.1143 0.1143)
			(layers "F.Cu" "F.Mask" "F.Paste")
			(net "P2E_CPU_NGFF_C_TX_DP14")
			(options
				(clearance outline)
				(anchor circle)
			)
			(primitives
				(gr_poly
					(pts
						(arc
							(start -0.254 -0.1778)
							(mid -0.239121 -0.213721)
							(end -0.2032 -0.2286)
						)
						(arc
							(start 0.2032 -0.2286)
							(mid 0.239121 -0.213721)
							(end 0.254 -0.1778)
						)
						(arc
							(start 0.254 0.1778)
							(mid 0.239121 0.213721)
							(end 0.2032 0.2286)
						)
						(arc
							(start -0.2032 0.2286)
							(mid -0.239121 0.213721)
							(end -0.254 0.1778)
						)
					)
					(width 0)
					(fill yes)
				)
			)
		)
	)
	(footprint ""
		(layer "F.Cu")
		(at 41.783 -49.53 180)
		(property "Reference" "C14"
			(at 0 0 180)
			(layer "F.SilkS")
			(hide yes)
			(effects
				(font
					(size 1.27 1.27)
				)
			)
		)
		(property "Value" "SC1U10V2KX-1GP"
			(at 1.8923 -1.2065 180)
			(unlocked yes)
			(layer "F.Fab")
			(hide yes)
			(effects
				(font
					(size 1.016 1.016)
					(thickness 0.1524)
				)
			)
		)
		(property "Device Type" "C402H22"
			(at 1.8923 -2.7305 180)
			(unlocked yes)
			(layer "F.Fab")
			(hide yes)
			(effects
				(font
					(size 1.016 1.016)
					(thickness 0.1524)
				)
			)
		)
		(duplicate_pad_numbers_are_jumpers no)
		(fp_rect
			(start -0.381 0.7366)
			(end 0.381 -0.7366)
			(stroke
				(width 0)
				(type default)
			)
			(fill no)
			(layer "F.CrtYd")
		)
		(fp_rect
			(start -0.381 0.7366)
			(end 0.381 -0.7366)
			(stroke
				(width 0)
				(type default)
			)
			(fill no)
			(layer "F.Fab")
		)
		(pad "1" smd custom
			(at 0 -0.4572 180)
			(size 0.1143 0.1143)
			(layers "F.Cu" "F.Mask" "F.Paste")
			(net "P3V3_CPU_DELAY_IN")
			(options
				(clearance outline)
				(anchor circle)
			)
			(primitives
				(gr_poly
					(pts
						(arc
							(start -0.254 -0.1778)
							(mid -0.239121 -0.213721)
							(end -0.2032 -0.2286)
						)
						(arc
							(start 0.2032 -0.2286)
							(mid 0.239121 -0.213721)
							(end 0.254 -0.1778)
						)
						(arc
							(start 0.254 0.1778)
							(mid 0.239121 0.213721)
							(end 0.2032 0.2286)
						)
						(arc
							(start -0.2032 0.2286)
							(mid -0.239121 0.213721)
							(end -0.254 0.1778)
						)
					)
					(width 0)
					(fill yes)
				)
			)
		)
		(pad "2" smd custom
			(at 0 0.4572 180)
			(size 0.1143 0.1143)
			(layers "F.Cu" "F.Mask" "F.Paste")
			(net "GND")
			(options
				(clearance outline)
				(anchor circle)
			)
			(primitives
				(gr_poly
					(pts
						(arc
							(start -0.254 -0.1778)
							(mid -0.239121 -0.213721)
							(end -0.2032 -0.2286)
						)
						(arc
							(start 0.2032 -0.2286)
							(mid 0.239121 -0.213721)
							(end 0.254 -0.1778)
						)
						(arc
							(start 0.254 0.1778)
							(mid 0.239121 0.213721)
							(end 0.2032 0.2286)
						)
						(arc
							(start -0.2032 0.2286)
							(mid -0.239121 0.213721)
							(end -0.254 0.1778)
						)
					)
					(width 0)
					(fill yes)
				)
			)
		)
	)
	(footprint ""
		(layer "F.Cu")
		(at 128.143 -36.068 -90)
		(property "Reference" "R29"
			(at 0 0 270)
			(layer "F.SilkS")
			(hide yes)
			(effects
				(font
					(size 1.27 1.27)
				)
			)
		)
		(property "Value" "33R2F-3-GP"
			(at 0.064008 -3.993896 270)
			(unlocked yes)
			(layer "F.Fab")
			(hide yes)
			(effects
				(font
					(size 1.016 1.016)
					(thickness 0.1524)
				)
			)
		)
		(property "Device Type" "R402H16"
			(at 0.064008 -5.517896 270)
			(unlocked yes)
			(layer "F.Fab")
			(hide yes)
			(effects
				(font
					(size 1.016 1.016)
					(thickness 0.1524)
				)
			)
		)
		(duplicate_pad_numbers_are_jumpers no)
		(fp_rect
			(start -0.381 0.8382)
			(end 0.381 -0.8382)
			(stroke
				(width 0)
				(type default)
			)
			(fill no)
			(layer "F.CrtYd")
		)
		(fp_rect
			(start -0.381 0.8382)
			(end 0.381 -0.8382)
			(stroke
				(width 0)
				(type default)
			)
			(fill no)
			(layer "F.Fab")
		)
		(pad "1" smd custom
			(at 0 -0.4318 270)
			(size 0.127 0.127)
			(layers "F.Cu" "F.Mask" "F.Paste")
			(net "LPC_AD_1")
			(options
				(clearance outline)
				(anchor circle)
			)
			(primitives
				(gr_poly
					(pts
						(arc
							(start -0.2032 -0.2794)
							(mid -0.239121 -0.264521)
							(end -0.254 -0.2286)
						)
						(arc
							(start -0.254 0.2286)
							(mid -0.239121 0.264521)
							(end -0.2032 0.2794)
						)
						(arc
							(start 0.2032 0.2794)
							(mid 0.239121 0.264521)
							(end 0.254 0.2286)
						)
						(arc
							(start 0.254 -0.2286)
							(mid 0.239121 -0.264521)
							(end 0.2032 -0.2794)
						)
					)
					(width 0)
					(fill yes)
				)
			)
		)
		(pad "2" smd custom
			(at 0 0.4318 270)
			(size 0.127 0.127)
			(layers "F.Cu" "F.Mask" "F.Paste")
			(net "LPC_CPU_LAD1")
			(options
				(clearance outline)
				(anchor circle)
			)
			(primitives
				(gr_poly
					(pts
						(arc
							(start -0.2032 -0.2794)
							(mid -0.239121 -0.264521)
							(end -0.254 -0.2286)
						)
						(arc
							(start -0.254 0.2286)
							(mid -0.239121 0.264521)
							(end -0.2032 0.2794)
						)
						(arc
							(start 0.2032 0.2794)
							(mid 0.239121 0.264521)
							(end 0.254 0.2286)
						)
						(arc
							(start 0.254 -0.2286)
							(mid 0.239121 -0.264521)
							(end 0.2032 -0.2794)
						)
					)
					(width 0)
					(fill yes)
				)
			)
		)
	)
	(footprint ""
		(layer "F.Cu")
		(at 5.715 -35.4076 -90)
		(property "Reference" "PC188"
			(at 0 0 270)
			(layer "F.SilkS")
			(hide yes)
			(effects
				(font
					(size 1.27 1.27)
				)
			)
		)
		(property "Value" "SC4D7U25V5KX-1-GP"
			(at 0 -4.9022 270)
			(unlocked yes)
			(layer "F.Fab")
			(hide yes)
			(effects
				(font
					(size 1.016 1.016)
					(thickness 0.1524)
				)
			)
		)
		(property "Device Type" "C805H58"
			(at 0 -6.8072 270)
			(unlocked yes)
			(layer "F.Fab")
			(hide yes)
			(effects
				(font
					(size 1.016 1.016)
					(thickness 0.1524)
				)
			)
		)
		(duplicate_pad_numbers_are_jumpers no)
		(fp_line
			(start 0.6096 0)
			(end -0.6096 0)
			(stroke
				(width 0.3048)
				(type default)
			)
			(layer "F.SilkS")
		)
		(fp_poly
			(pts
				(xy -0.9017 1.4351) (xy 0.9017 1.4351) (xy 0.9017 -1.4351) (xy -0.9017 -1.4351)
			)
			(stroke
				(width 0)
				(type default)
			)
			(fill no)
			(layer "F.CrtYd")
		)
		(fp_poly
			(pts
				(xy 0.9017 1.4351) (xy 0.9017 -1.4351) (xy -0.9017 -1.4351) (xy -0.9017 1.4351)
			)
			(stroke
				(width 0)
				(type default)
			)
			(fill no)
			(layer "F.Fab")
		)
		(pad "1" smd rect
			(at 0 -0.8382 270)
			(size 1.5494 0.9398)
			(layers "F.Cu" "F.Mask" "F.Paste")
			(net "P3V3_STBY_VDD")
		)
		(pad "2" smd rect
			(at 0 0.8382 270)
			(size 1.5494 0.9398)
			(layers "F.Cu" "F.Mask" "F.Paste")
			(net "GND")
		)
	)
	(footprint ""
		(layer "F.Cu")
		(at 11.049 -36.449 -90)
		(property "Reference" "PU15"
			(at 0 0 270)
			(layer "F.SilkS")
			(hide yes)
			(effects
				(font
					(size 1.27 1.27)
				)
			)
		)
		(property "Value" "TPS53318DQPR-GP"
			(at -4.298442 -3.894328 270)
			(unlocked yes)
			(layer "F.Fab")
			(hide yes)
			(effects
				(font
					(size 1.016 1.016)
					(thickness 0.1524)
				)
			)
		)
		(property "Device Type" "DFN22G6050-G6133H60"
			(at -4.298442 -5.418328 270)
			(unlocked yes)
			(layer "F.Fab")
			(hide yes)
			(effects
				(font
					(size 1.016 1.016)
					(thickness 0.1524)
				)
			)
		)
		(duplicate_pad_numbers_are_jumpers no)
		(fp_poly
			(pts
				(xy 2.508504 -2.882138) (xy 2.986024 -3.359912) (xy 2.03073 -3.359912)
			)
			(stroke
				(width 0)
				(type default)
			)
			(fill yes)
			(layer "F.SilkS")
		)
		(fp_rect
			(start -3.2512 2.8829)
			(end 3.2512 -2.8829)
			(stroke
				(width 0)
				(type default)
			)
			(fill no)
			(layer "F.CrtYd")
		)
		(fp_rect
			(start -3.2512 2.8829)
			(end 3.2512 -2.8829)
			(stroke
				(width 0)
				(type default)
			)
			(fill no)
			(layer "F.Fab")
		)
		(pad "1" smd rect
			(at 2.500122 -2.322322 270)
			(size 0.3048 0.8636)
			(layers "F.Cu" "F.Mask" "F.Paste")
			(net "P3V3_STBY_VFB")
		)
		(pad "2" smd rect
			(at 1.999996 -2.322322 270)
			(size 0.3048 0.8636)
			(layers "F.Cu" "F.Mask" "F.Paste")
			(net "P3V3_STBY_EN")
		)
		(pad "3" smd rect
			(at 1.500124 -2.322322 270)
			(size 0.3048 0.8636)
			(layers "F.Cu" "F.Mask" "F.Paste")
			(net "P3V3_STBY_PG")
		)
		(pad "4" smd rect
			(at 0.999998 -2.322322 270)
			(size 0.3048 0.8636)
			(layers "F.Cu" "F.Mask" "F.Paste")
			(net "P3V3_STBY_VBST")
		)
		(pad "5" smd rect
			(at 0.500126 -2.322322 270)
			(size 0.3048 0.8636)
			(layers "F.Cu" "F.Mask" "F.Paste")
			(net "P3V3_STBY_ROVP")
		)
		(pad "6" smd rect
			(at 0 -2.322322 270)
			(size 0.3048 0.8636)
			(layers "F.Cu" "F.Mask" "F.Paste")
			(net "P3V3_STBY_LL")
		)
		(pad "7" smd rect
			(at -0.500126 -2.322322 270)
			(size 0.3048 0.8636)
			(layers "F.Cu" "F.Mask" "F.Paste")
			(net "P3V3_STBY_LL")
		)
		(pad "8" smd rect
			(at -0.999998 -2.322322 270)
			(size 0.3048 0.8636)
			(layers "F.Cu" "F.Mask" "F.Paste")
			(net "P3V3_STBY_LL")
		)
		(pad "9" smd rect
			(at -1.500124 -2.322322 270)
			(size 0.3048 0.8636)
			(layers "F.Cu" "F.Mask" "F.Paste")
			(net "P3V3_STBY_LL")
		)
		(pad "10" smd rect
			(at -1.999996 -2.322322 270)
			(size 0.3048 0.8636)
			(layers "F.Cu" "F.Mask" "F.Paste")
			(net "P3V3_STBY_LL")
		)
		(pad "11" smd rect
			(at -2.500122 -2.322322 270)
			(size 0.3048 0.8636)
			(layers "F.Cu" "F.Mask" "F.Paste")
			(net "P3V3_STBY_LL")
		)
		(pad "12" smd rect
			(at -2.500122 2.322322 270)
			(size 0.3048 0.8636)
			(layers "F.Cu" "F.Mask" "F.Paste")
			(net "P3V3_STBY_VIN")
		)
		(pad "13" smd rect
			(at -1.999996 2.322322 270)
			(size 0.3048 0.8636)
			(layers "F.Cu" "F.Mask" "F.Paste")
			(net "P3V3_STBY_VIN")
		)
		(pad "14" smd rect
			(at -1.500124 2.322322 270)
			(size 0.3048 0.8636)
			(layers "F.Cu" "F.Mask" "F.Paste")
			(net "P3V3_STBY_VIN")
		)
		(pad "15" smd rect
			(at -0.999998 2.322322 270)
			(size 0.3048 0.8636)
			(layers "F.Cu" "F.Mask" "F.Paste")
			(net "P3V3_STBY_VIN")
		)
		(pad "16" smd rect
			(at -0.500126 2.322322 270)
			(size 0.3048 0.8636)
			(layers "F.Cu" "F.Mask" "F.Paste")
			(net "P3V3_STBY_VIN")
		)
		(pad "17" smd rect
			(at 0 2.322322 270)
			(size 0.3048 0.8636)
			(layers "F.Cu" "F.Mask" "F.Paste")
			(net "P3V3_STBY_VIN")
		)
		(pad "18" smd rect
			(at 0.500126 2.322322 270)
			(size 0.3048 0.8636)
			(layers "F.Cu" "F.Mask" "F.Paste")
			(net "P3V3_STBY_VREG")
		)
		(pad "19" smd rect
			(at 0.999998 2.322322 270)
			(size 0.3048 0.8636)
			(layers "F.Cu" "F.Mask" "F.Paste")
			(net "P3V3_STBY_VDD")
		)
		(pad "20" smd rect
			(at 1.500124 2.322322 270)
			(size 0.3048 0.8636)
			(layers "F.Cu" "F.Mask" "F.Paste")
			(net "P3V3_STBY_MODE")
		)
		(pad "21" smd rect
			(at 1.999996 2.322322 270)
			(size 0.3048 0.8636)
			(layers "F.Cu" "F.Mask" "F.Paste")
			(net "P3V3_STBY_TRIP")
		)
		(pad "22" smd rect
			(at 2.500122 2.322322 270)
			(size 0.3048 0.8636)
			(layers "F.Cu" "F.Mask" "F.Paste")
			(net "P3V3_STBY_RF")
		)
		(pad "23" smd custom
			(at 0 0 270)
			(size 0.83185 0.83185)
			(layers "F.Cu" "F.Mask" "F.Paste")
			(net "GND")
			(options
				(clearance outline)
				(anchor circle)
			)
			(primitives
				(gr_poly
					(pts
						(xy -2.7813 1.6637) (xy -2.7813 1.2954) (xy -3.048 1.2954) (xy -3.048 0.9525) (xy -2.7813 0.9525)
						(xy -2.7813 -0.9525) (xy -3.048 -0.9525) (xy -3.048 -1.2954) (xy -2.7813 -1.2954) (xy -2.7813 -1.6637)
						(xy 2.7813 -1.6637) (xy 2.7813 -1.2954) (xy 3.048 -1.2954) (xy 3.048 -0.9525) (xy 2.7813 -0.9525)
						(xy 2.7813 0.9525) (xy 3.048 0.9525) (xy 3.048 1.2954) (xy 2.7813 1.2954) (xy 2.7813 1.6637)
					)
					(width 0)
					(fill yes)
				)
			)
		)
	)
	(footprint ""
		(layer "F.Cu")
		(at 14.478 -31.877 180)
		(property "Reference" "R319"
			(at 0 0 180)
			(layer "F.SilkS")
			(hide yes)
			(effects
				(font
					(size 1.27 1.27)
				)
			)
		)
		(property "Value" "2K2R2F-GP"
			(at 1.7907 -1.1176 180)
			(unlocked yes)
			(layer "F.Fab")
			(hide yes)
			(effects
				(font
					(size 1.016 1.016)
					(thickness 0.1524)
				)
			)
		)
		(property "Device Type" "R402H16"
			(at 1.7907 -2.6416 180)
			(unlocked yes)
			(layer "F.Fab")
			(hide yes)
			(effects
				(font
					(size 1.016 1.016)
					(thickness 0.1524)
				)
			)
		)
		(duplicate_pad_numbers_are_jumpers no)
		(fp_rect
			(start -0.381 0.8382)
			(end 0.381 -0.8382)
			(stroke
				(width 0)
				(type default)
			)
			(fill no)
			(layer "F.CrtYd")
		)
		(fp_rect
			(start -0.381 0.8382)
			(end 0.381 -0.8382)
			(stroke
				(width 0)
				(type default)
			)
			(fill no)
			(layer "F.Fab")
		)
		(pad "1" smd custom
			(at 0 -0.4318 180)
			(size 0.127 0.127)
			(layers "F.Cu" "F.Mask" "F.Paste")
			(net "AGND_P3V3_STBY")
			(options
				(clearance outline)
				(anchor circle)
			)
			(primitives
				(gr_poly
					(pts
						(arc
							(start -0.2032 -0.2794)
							(mid -0.239121 -0.264521)
							(end -0.254 -0.2286)
						)
						(arc
							(start -0.254 0.2286)
							(mid -0.239121 0.264521)
							(end -0.2032 0.2794)
						)
						(arc
							(start 0.2032 0.2794)
							(mid 0.239121 0.264521)
							(end 0.254 0.2286)
						)
						(arc
							(start 0.254 -0.2286)
							(mid 0.239121 -0.264521)
							(end 0.2032 -0.2794)
						)
					)
					(width 0)
					(fill yes)
				)
			)
		)
		(pad "2" smd custom
			(at 0 0.4318 180)
			(size 0.127 0.127)
			(layers "F.Cu" "F.Mask" "F.Paste")
			(net "P3V3_STBY_EN")
			(options
				(clearance outline)
				(anchor circle)
			)
			(primitives
				(gr_poly
					(pts
						(arc
							(start -0.2032 -0.2794)
							(mid -0.239121 -0.264521)
							(end -0.254 -0.2286)
						)
						(arc
							(start -0.254 0.2286)
							(mid -0.239121 0.264521)
							(end -0.2032 0.2794)
						)
						(arc
							(start 0.2032 0.2794)
							(mid 0.239121 0.264521)
							(end 0.254 0.2286)
						)
						(arc
							(start 0.254 -0.2286)
							(mid 0.239121 -0.264521)
							(end 0.2032 -0.2794)
						)
					)
					(width 0)
					(fill yes)
				)
			)
		)
	)
	(footprint ""
		(layer "F.Cu")
		(at 15.7988 -34.29)
		(property "Reference" "PR193"
			(at 0 0 0)
			(layer "F.SilkS")
			(hide yes)
			(effects
				(font
					(size 1.27 1.27)
				)
			)
		)
		(property "Value" "3D01R5F-GP"
			(at 0 -4.9022 0)
			(unlocked yes)
			(layer "F.Fab")
			(hide yes)
			(effects
				(font
					(size 1.016 1.016)
					(thickness 0.1524)
				)
			)
		)
		(property "Device Type" "R805H24"
			(at 0 -6.8072 0)
			(unlocked yes)
			(layer "F.Fab")
			(hide yes)
			(effects
				(font
					(size 1.016 1.016)
					(thickness 0.1524)
				)
			)
		)
		(duplicate_pad_numbers_are_jumpers no)
		(fp_line
			(start -0.2794 0)
			(end -0.6096 0)
			(stroke
				(width 0.3048)
				(type default)
			)
			(layer "F.SilkS")
		)
		(fp_line
			(start 0.6096 0)
			(end 0.2794 0)
			(stroke
				(width 0.3048)
				(type default)
			)
			(layer "F.SilkS")
		)
		(fp_poly
			(pts
				(xy -0.9017 1.4351) (xy 0.9017 1.4351) (xy 0.9017 -1.4351) (xy -0.9017 -1.4351)
			)
			(stroke
				(width 0)
				(type default)
			)
			(fill no)
			(layer "F.CrtYd")
		)
		(fp_poly
			(pts
				(xy 0.9017 1.4351) (xy 0.9017 -1.4351) (xy -0.9017 -1.4351) (xy -0.9017 1.4351)
			)
			(stroke
				(width 0)
				(type default)
			)
			(fill no)
			(layer "F.Fab")
		)
		(pad "1" smd rect
			(at 0 -0.8382)
			(size 1.5494 0.9398)
			(layers "F.Cu" "F.Mask" "F.Paste")
			(net "P3V3_STBY_VBST")
		)
		(pad "2" smd rect
			(at 0 0.8382)
			(size 1.5494 0.9398)
			(layers "F.Cu" "F.Mask" "F.Paste")
			(net "P3V3_STBY_VBST_RC")
		)
	)
)
